# BASEBOARD_FAB2 (Tioga Pass) — schematic netlist excerpt (pin names and nets, part order shuffled) for the footprints in the layout excerpt that follows; sources: Cadence DE-HDL packaged netlist, KiCad conversion of Wiwynn_Tioga_Pass_MB.brd

C7A41  CAP  0.22UF 16V 10% X7R  pkg 0402  page 236 : A = P5V_STBY ; B = GND
C1F15  CAP  0.22UF 16V 10% X7R  pkg 0402  page 181 : A = P3E_CPU1_PE3_MP_C_TXN<2> ; B = P3E_CPU1_PE3_MP_TXN<2>
C2D7  CAP_A  22.0UF 4V 20% X6S  pkg 0603V  page 228 : A = PVDDQ_KLM ; B = GND

(kicad_pcb
	(version 20260206)
	(generator "pcbnew")
	(generator_version "10.0")
	(general
		(thickness 1.6)
		(legacy_teardrops no)
	)
	(paper "A4")
	(title_block
		(title "Wiwynn_Tioga_Pass_MB.brd")
		(comment 1 "Tioga Pass / footprints 1652-1654 of 4770")
	)
	(layers
		(0 "F.Cu" signal "TOP")
		(4 "In1.Cu" signal "L2GND")
		(6 "In2.Cu" signal "L3")
		(8 "In3.Cu" signal "L4GND")
		(10 "In4.Cu" signal "L5")
		(12 "In5.Cu" signal "L6GND")
		(14 "In6.Cu" signal "L7VCC")
		(16 "In7.Cu" signal "L8VCC")
		(18 "In8.Cu" signal "L9GND")
		(20 "In9.Cu" signal "L10")
		(22 "In10.Cu" signal "L11GND")
		(24 "In11.Cu" signal "L12")
		(26 "In12.Cu" signal "L13GND")
		(2 "B.Cu" signal "BOTTOM")
		(9 "F.Adhes" user "F.Adhesive")
		(11 "B.Adhes" user "B.Adhesive")
		(13 "F.Paste" user "Package Geometry/Pastemask Top")
		(15 "B.Paste" user "Package Geometry/Pastemask Bottom")
		(5 "F.SilkS" user "Ref Des/Silkscreen Top")
		(7 "B.SilkS" user "Ref Des/Silkscreen Bottom")
		(1 "F.Mask" user "Board Geometry/Soldermask Top")
		(3 "B.Mask" user "Board Geometry/Soldermask Bottom")
		(17 "Dwgs.User" user "User.Drawings")
		(19 "Cmts.User" user "User.Comments")
		(21 "Eco1.User" user "User.Eco1")
		(23 "Eco2.User" user "User.Eco2")
		(25 "Edge.Cuts" user "Board Geometry/Outline")
		(27 "Margin" user)
		(31 "F.CrtYd" user "Package Geometry/Place Bound Top")
		(29 "B.CrtYd" user "Package Geometry/Place Bound Bottom")
		(35 "F.Fab" user "Ref Des/Assembly Top")
		(33 "B.Fab" user "Ref Des/Assembly Bottom")
	)
	(footprint ""
		(layer "F.Cu")
		(at 381.576072 -154.416506)
		(property "Reference" "C7A41"
			(at 0 0 0)
			(layer "F.SilkS")
			(hide yes)
			(effects
				(font
					(size 1.27 1.27)
				)
			)
		)
		(property "Value" ""
			(at 0 0 0)
			(layer "F.Fab")
			(effects
				(font
					(size 1.27 1.27)
				)
			)
		)
		(duplicate_pad_numbers_are_jumpers no)
		(fp_poly
			(pts
				(xy 0.3048 -0.1016) (xy 0.3048 0.9906) (xy -0.3048 0.9906) (xy -0.3048 -0.1016)
			)
			(stroke
				(width 0)
				(type default)
			)
			(fill no)
			(layer "F.CrtYd")
		)
		(fp_line
			(start -0.3048 -0.1016)
			(end -0.3048 0.9906)
			(stroke
				(width 0.1)
				(type default)
			)
			(layer "F.Fab")
		)
		(fp_line
			(start -0.3048 0.9906)
			(end 0.3048 0.9906)
			(stroke
				(width 0.1)
				(type default)
			)
			(layer "F.Fab")
		)
		(fp_line
			(start 0.3048 -0.1016)
			(end -0.3048 -0.1016)
			(stroke
				(width 0.1)
				(type default)
			)
			(layer "F.Fab")
		)
		(fp_line
			(start 0.3048 0.9906)
			(end 0.3048 -0.1016)
			(stroke
				(width 0.1)
				(type default)
			)
			(layer "F.Fab")
		)
		(pad "1" smd rect
			(at 0 0)
			(size 0.508 0.508)
			(layers "F.Cu" "F.Mask" "F.Paste")
			(net "P5V_STBY")
		)
		(pad "2" smd rect
			(at 0 0.889)
			(size 0.508 0.508)
			(layers "F.Cu" "F.Mask" "F.Paste")
			(net "GND")
		)
		(zone
			(layer "F.Cu")
			(hatch none 0.5)
			(connect_pads
				(clearance 0)
			)
			(min_thickness 0.25)
			(keepout
				(tracks allowed)
				(vias not_allowed)
				(pads allowed)
				(copperpour not_allowed)
				(footprints allowed)
			)
			(placement
				(enabled no)
				(sheetname "")
			)
			(fill
				(thermal_gap 0.5)
				(thermal_bridge_width 0.5)
				(island_removal_mode 0)
			)
			(polygon
				(pts
					(xy 381.322072 -154.162506) (xy 381.830072 -154.162506) (xy 381.830072 -153.781506) (xy 381.322072 -153.781506)
				)
			)
		)
		(zone
			(layer "F.Cu")
			(hatch none 0.5)
			(connect_pads
				(clearance 0)
			)
			(min_thickness 0.25)
			(keepout
				(tracks not_allowed)
				(vias allowed)
				(pads allowed)
				(copperpour not_allowed)
				(footprints allowed)
			)
			(placement
				(enabled no)
				(sheetname "")
			)
			(fill
				(thermal_gap 0.5)
				(thermal_bridge_width 0.5)
				(island_removal_mode 0)
			)
			(polygon
				(pts
					(xy 381.322072 -153.781506) (xy 381.830072 -153.781506) (xy 381.830072 -154.162506) (xy 381.322072 -154.162506)
				)
			)
		)
	)
	(footprint ""
		(layer "F.Cu")
		(at 98.524568 -84.709)
		(property "Reference" "C2D7"
			(at 0 0 0)
			(layer "F.SilkS")
			(hide yes)
			(effects
				(font
					(size 1.27 1.27)
				)
			)
		)
		(property "Value" ""
			(at 0 0 0)
			(layer "F.Fab")
			(effects
				(font
					(size 1.27 1.27)
				)
			)
		)
		(duplicate_pad_numbers_are_jumpers no)
		(fp_poly
			(pts
				(xy -0.4953 -0.2032) (xy 0.4953 -0.2032) (xy 0.4953 1.6002) (xy -0.4953 1.6002)
			)
			(stroke
				(width 0)
				(type default)
			)
			(fill no)
			(layer "F.CrtYd")
		)
		(fp_line
			(start -0.4953 -0.2032)
			(end 0.4953 -0.2032)
			(stroke
				(width 0.1)
				(type default)
			)
			(layer "F.Fab")
		)
		(fp_line
			(start -0.4953 1.6002)
			(end -0.4953 -0.2032)
			(stroke
				(width 0.1)
				(type default)
			)
			(layer "F.Fab")
		)
		(fp_line
			(start 0.4953 -0.2032)
			(end 0.4953 1.6002)
			(stroke
				(width 0.1)
				(type default)
			)
			(layer "F.Fab")
		)
		(fp_line
			(start 0.4953 1.6002)
			(end -0.4953 1.6002)
			(stroke
				(width 0.1)
				(type default)
			)
			(layer "F.Fab")
		)
		(pad "1" smd rect
			(at 0 0)
			(size 0.762 0.889)
			(layers "F.Cu" "F.Mask" "F.Paste")
			(net "PVDDQ_KLM")
		)
		(pad "2" smd rect
			(at 0 1.397)
			(size 0.762 0.889)
			(layers "F.Cu" "F.Mask" "F.Paste")
			(net "GND")
		)
		(zone
			(layer "F.Cu")
			(hatch none 0.5)
			(connect_pads
				(clearance 0)
			)
			(min_thickness 0.25)
			(keepout
				(tracks not_allowed)
				(vias allowed)
				(pads allowed)
				(copperpour not_allowed)
				(footprints allowed)
			)
			(placement
				(enabled no)
				(sheetname "")
			)
			(fill
				(thermal_gap 0.5)
				(thermal_bridge_width 0.5)
				(island_removal_mode 0)
			)
			(polygon
				(pts
					(xy 98.143568 -84.2645) (xy 98.905568 -84.2645) (xy 98.905568 -83.7565) (xy 98.143568 -83.7565)
				)
			)
		)
	)
	(footprint ""
		(layer "F.Cu")
		(at 13.8938 -26.797 90)
		(property "Reference" "C1F15"
			(at 0 0 90)
			(layer "F.SilkS")
			(hide yes)
			(effects
				(font
					(size 1.27 1.27)
				)
			)
		)
		(property "Value" ""
			(at 0 0 90)
			(layer "F.Fab")
			(effects
				(font
					(size 1.27 1.27)
				)
			)
		)
		(duplicate_pad_numbers_are_jumpers no)
		(fp_rect
			(start -0.3048 -0.1016)
			(end 0.3048 0.9906)
			(stroke
				(width 0)
				(type default)
			)
			(fill no)
			(layer "F.CrtYd")
		)
		(fp_line
			(start 0.3048 -0.1016)
			(end -0.3048 -0.1016)
			(stroke
				(width 0.1)
				(type default)
			)
			(layer "F.Fab")
		)
		(fp_line
			(start -0.3048 -0.1016)
			(end -0.3048 0.9906)
			(stroke
				(width 0.1)
				(type default)
			)
			(layer "F.Fab")
		)
		(fp_line
			(start 0.3048 0.9906)
			(end 0.3048 -0.1016)
			(stroke
				(width 0.1)
				(type default)
			)
			(layer "F.Fab")
		)
		(fp_line
			(start -0.3048 0.9906)
			(end 0.3048 0.9906)
			(stroke
				(width 0.1)
				(type default)
			)
			(layer "F.Fab")
		)
		(pad "1" smd rect
			(at 0 0 90)
			(size 0.508 0.508)
			(layers "F.Cu" "F.Mask" "F.Paste")
			(net "P3E_CPU1_PE3_MP_C_TXN<2>")
		)
		(pad "2" smd rect
			(at 0 0.889 90)
			(size 0.508 0.508)
			(layers "F.Cu" "F.Mask" "F.Paste")
			(net "P3E_CPU1_PE3_MP_TXN<2>")
		)
		(zone
			(layer "F.Cu")
			(hatch none 0.5)
			(connect_pads
				(clearance 0)
			)
			(min_thickness 0.25)
			(keepout
				(tracks not_allowed)
				(vias allowed)
				(pads allowed)
				(copperpour not_allowed)
				(footprints allowed)
			)
			(placement
				(enabled no)
				(sheetname "")
			)
			(fill
				(thermal_gap 0.5)
				(thermal_bridge_width 0.5)
				(island_removal_mode 0)
			)
			(polygon
				(pts
					(xy 14.1478 -26.543) (xy 14.5288 -26.543) (xy 14.5288 -27.051) (xy 14.1478 -27.051)
				)
			)
		)
		(zone
			(layer "F.Cu")
			(hatch none 0.5)
			(connect_pads
				(clearance 0)
			)
			(min_thickness 0.25)
			(keepout
				(tracks allowed)
				(vias not_allowed)
				(pads allowed)
				(copperpour not_allowed)
				(footprints allowed)
			)
			(placement
				(enabled no)
				(sheetname "")
			)
			(fill
				(thermal_gap 0.5)
				(thermal_bridge_width 0.5)
				(island_removal_mode 0)
			)
			(polygon
				(pts
					(xy 14.1478 -26.543) (xy 14.5288 -26.543) (xy 14.5288 -27.051) (xy 14.1478 -27.051)
				)
			)
		)
	)
)
